# BASEBOARD_FAB2 (Tioga Pass) — schematic netlist excerpt (pin names and nets, part order shuffled) for the footprints in the layout excerpt that follows; sources: Cadence DE-HDL packaged netlist, KiCad conversion of Wiwynn_Tioga_Pass_MB.brd

R1T30  RES  1.00K 1% CHIP  pkg 0402  page 151 : A = P1V2_AUX_BMC ; B = BMC_M_VREFCA
R9P13  270KR2F-GP  1%  pkg RCL_GP  page 200 : \1\ = P12V_STBY ; \2\ = A_P12V_STBY_FP_TRIGGER
C1L20  CAP_A  0.01UF 25V 10% X7R  pkg 0402V  page 113 : A = P3V3_STBY ; B = GND

(kicad_pcb
	(version 20260206)
	(generator "pcbnew")
	(generator_version "10.0")
	(general
		(thickness 1.6)
		(legacy_teardrops no)
	)
	(paper "A4")
	(title_block
		(title "Wiwynn_Tioga_Pass_MB.brd")
		(comment 1 "Tioga Pass / footprints 2937-2939 of 4770")
	)
	(layers
		(0 "F.Cu" signal "TOP")
		(4 "In1.Cu" signal "L2GND")
		(6 "In2.Cu" signal "L3")
		(8 "In3.Cu" signal "L4GND")
		(10 "In4.Cu" signal "L5")
		(12 "In5.Cu" signal "L6GND")
		(14 "In6.Cu" signal "L7VCC")
		(16 "In7.Cu" signal "L8VCC")
		(18 "In8.Cu" signal "L9GND")
		(20 "In9.Cu" signal "L10")
		(22 "In10.Cu" signal "L11GND")
		(24 "In11.Cu" signal "L12")
		(26 "In12.Cu" signal "L13GND")
		(2 "B.Cu" signal "BOTTOM")
		(9 "F.Adhes" user "F.Adhesive")
		(11 "B.Adhes" user "B.Adhesive")
		(13 "F.Paste" user "Package Geometry/Pastemask Top")
		(15 "B.Paste" user "Package Geometry/Pastemask Bottom")
		(5 "F.SilkS" user "Ref Des/Silkscreen Top")
		(7 "B.SilkS" user "Ref Des/Silkscreen Bottom")
		(1 "F.Mask" user "Board Geometry/Soldermask Top")
		(3 "B.Mask" user "Board Geometry/Soldermask Bottom")
		(17 "Dwgs.User" user "User.Drawings")
		(19 "Cmts.User" user "User.Comments")
		(21 "Eco1.User" user "User.Eco1")
		(23 "Eco2.User" user "User.Eco2")
		(25 "Edge.Cuts" user "Board Geometry/Outline")
		(27 "Margin" user)
		(31 "F.CrtYd" user "Package Geometry/Place Bound Top")
		(29 "B.CrtYd" user "Package Geometry/Place Bound Bottom")
		(35 "F.Fab" user "Ref Des/Assembly Top")
		(33 "B.Fab" user "Ref Des/Assembly Bottom")
	)
	(footprint ""
		(layer "B.Cu")
		(at 466.852 -140.3604 90)
		(property "Reference" "C1L20"
			(at 0 0 90)
			(layer "B.SilkS")
			(hide yes)
			(effects
				(font
					(size 1.27 1.27)
				)
				(justify mirror)
			)
		)
		(property "Value" ""
			(at 0 0 90)
			(layer "B.Fab")
			(effects
				(font
					(size 1.27 1.27)
				)
				(justify mirror)
			)
		)
		(duplicate_pad_numbers_are_jumpers no)
		(fp_poly
			(pts
				(xy -0.3048 -0.1016) (xy -0.3048 0.9906) (xy 0.3048 0.9906) (xy 0.3048 -0.1016)
			)
			(stroke
				(width 0)
				(type default)
			)
			(fill no)
			(layer "B.CrtYd")
		)
		(fp_line
			(start 0.3048 -0.1016)
			(end 0.3048 0.9906)
			(stroke
				(width 0.1)
				(type default)
			)
			(layer "B.Fab")
		)
		(fp_line
			(start -0.3048 -0.1016)
			(end 0.3048 -0.1016)
			(stroke
				(width 0.1)
				(type default)
			)
			(layer "B.Fab")
		)
		(fp_line
			(start 0.3048 0.9906)
			(end -0.3048 0.9906)
			(stroke
				(width 0.1)
				(type default)
			)
			(layer "B.Fab")
		)
		(fp_line
			(start -0.3048 0.9906)
			(end -0.3048 -0.1016)
			(stroke
				(width 0.1)
				(type default)
			)
			(layer "B.Fab")
		)
		(pad "1" smd rect
			(at 0 0 270)
			(size 0.508 0.508)
			(layers "B.Cu" "B.Mask" "B.Paste")
			(net "P3V3_STBY")
		)
		(pad "2" smd rect
			(at 0 0.889 270)
			(size 0.508 0.508)
			(layers "B.Cu" "B.Mask" "B.Paste")
			(net "GND")
		)
		(zone
			(layer "B.Cu")
			(hatch none 0.5)
			(connect_pads
				(clearance 0)
			)
			(min_thickness 0.25)
			(keepout
				(tracks allowed)
				(vias not_allowed)
				(pads allowed)
				(copperpour not_allowed)
				(footprints allowed)
			)
			(placement
				(enabled no)
				(sheetname "")
			)
			(fill
				(thermal_gap 0.5)
				(thermal_bridge_width 0.5)
				(island_removal_mode 0)
			)
			(polygon
				(pts
					(xy 467.106 -140.6144) (xy 467.106 -140.1064) (xy 467.487 -140.1064) (xy 467.487 -140.6144)
				)
			)
		)
		(zone
			(layer "B.Cu")
			(hatch none 0.5)
			(connect_pads
				(clearance 0)
			)
			(min_thickness 0.25)
			(keepout
				(tracks not_allowed)
				(vias allowed)
				(pads allowed)
				(copperpour not_allowed)
				(footprints allowed)
			)
			(placement
				(enabled no)
				(sheetname "")
			)
			(fill
				(thermal_gap 0.5)
				(thermal_bridge_width 0.5)
				(island_removal_mode 0)
			)
			(polygon
				(pts
					(xy 467.487 -140.6144) (xy 467.487 -140.1064) (xy 467.106 -140.1064) (xy 467.106 -140.6144)
				)
			)
		)
	)
	(footprint ""
		(layer "B.Cu")
		(at 448.19189 -29.6164 -90)
		(property "Reference" "R1T30"
			(at 0 0 90)
			(layer "B.SilkS")
			(hide yes)
			(effects
				(font
					(size 1.27 1.27)
				)
				(justify mirror)
			)
		)
		(property "Value" ""
			(at 0 0 90)
			(layer "B.Fab")
			(effects
				(font
					(size 1.27 1.27)
				)
				(justify mirror)
			)
		)
		(duplicate_pad_numbers_are_jumpers no)
		(fp_poly
			(pts
				(xy 0.2794 -0.1016) (xy -0.2794 -0.1016) (xy -0.2794 0.9906) (xy 0.2794 0.9906)
			)
			(stroke
				(width 0)
				(type default)
			)
			(fill no)
			(layer "B.CrtYd")
		)
		(fp_line
			(start -0.2794 0.9906)
			(end -0.2794 -0.1016)
			(stroke
				(width 0.1)
				(type default)
			)
			(layer "B.Fab")
		)
		(fp_line
			(start 0.2794 0.9906)
			(end -0.2794 0.9906)
			(stroke
				(width 0.1)
				(type default)
			)
			(layer "B.Fab")
		)
		(fp_line
			(start -0.2794 -0.1016)
			(end 0.2794 -0.1016)
			(stroke
				(width 0.1)
				(type default)
			)
			(layer "B.Fab")
		)
		(fp_line
			(start 0.2794 -0.1016)
			(end 0.2794 0.9906)
			(stroke
				(width 0.1)
				(type default)
			)
			(layer "B.Fab")
		)
		(pad "1" smd rect
			(at 0 0 90)
			(size 0.508 0.508)
			(layers "B.Cu" "B.Mask" "B.Paste")
			(net "P1V2_AUX_BMC")
		)
		(pad "2" smd rect
			(at 0 0.889 90)
			(size 0.508 0.508)
			(layers "B.Cu" "B.Mask" "B.Paste")
			(net "BMC_M_VREFCA")
		)
		(zone
			(layer "B.Cu")
			(hatch none 0.5)
			(connect_pads
				(clearance 0)
			)
			(min_thickness 0.25)
			(keepout
				(tracks not_allowed)
				(vias allowed)
				(pads allowed)
				(copperpour not_allowed)
				(footprints allowed)
			)
			(placement
				(enabled no)
				(sheetname "")
			)
			(fill
				(thermal_gap 0.5)
				(thermal_bridge_width 0.5)
				(island_removal_mode 0)
			)
			(polygon
				(pts
					(xy 447.55689 -29.3624) (xy 447.55689 -29.8704) (xy 447.93789 -29.8704) (xy 447.93789 -29.3624)
				)
			)
		)
		(zone
			(layer "B.Cu")
			(hatch none 0.5)
			(connect_pads
				(clearance 0)
			)
			(min_thickness 0.25)
			(keepout
				(tracks allowed)
				(vias not_allowed)
				(pads allowed)
				(copperpour not_allowed)
				(footprints allowed)
			)
			(placement
				(enabled no)
				(sheetname "")
			)
			(fill
				(thermal_gap 0.5)
				(thermal_bridge_width 0.5)
				(island_removal_mode 0)
			)
			(polygon
				(pts
					(xy 447.93789 -29.3624) (xy 447.93789 -29.8704) (xy 447.55689 -29.8704) (xy 447.55689 -29.3624)
				)
			)
		)
	)
	(footprint ""
		(layer "B.Cu")
		(at 20.888706 -81.520792 -90)
		(property "Reference" "R9P13"
			(at 0 0 90)
			(layer "B.SilkS")
			(hide yes)
			(effects
				(font
					(size 1.27 1.27)
				)
				(justify mirror)
			)
		)
		(property "Value" "*"
			(at -0.064008 -4.108196 270)
			(unlocked yes)
			(layer "B.Fab")
			(hide yes)
			(effects
				(font
					(size 1.27 1.016)
					(thickness 0.1524)
				)
				(justify mirror)
			)
		)
		(property "Device Type" "270KR2F-GP_RCL_GP-270KR2F-GP,6A"
			(at -0.064008 -5.632196 270)
			(unlocked yes)
			(layer "B.Fab")
			(hide yes)
			(effects
				(font
					(size 1.27 1.016)
					(thickness 0.1524)
				)
				(justify mirror)
			)
		)
		(duplicate_pad_numbers_are_jumpers no)
		(fp_line
			(start -0.508 -0.9398)
			(end 0.508 -0.9398)
			(stroke
				(width 0.1524)
				(type default)
			)
			(layer "B.SilkS")
		)
		(fp_line
			(start 0.508 -0.9398)
			(end 0.508 0.9398)
			(stroke
				(width 0.1524)
				(type default)
			)
			(layer "B.SilkS")
		)
		(fp_rect
			(start 0.508 0.9398)
			(end -0.508 -0.9398)
			(stroke
				(width 0)
				(type default)
			)
			(fill no)
			(layer "B.CrtYd")
		)
		(fp_rect
			(start 0.508 0.9398)
			(end -0.508 -0.9398)
			(stroke
				(width 0)
				(type default)
			)
			(fill no)
			(layer "B.Fab")
		)
		(pad "1" smd custom
			(at 0 -0.4445 90)
			(size 0.1397 0.1397)
			(layers "B.Cu" "B.Mask" "B.Paste")
			(net "P12V_STBY")
			(options
				(clearance outline)
				(anchor circle)
			)
			(primitives
				(gr_poly
					(pts
						(arc
							(start -0.1778 0.2794)
							(mid -0.249642 0.249642)
							(end -0.2794 0.1778)
						)
						(arc
							(start -0.2794 -0.1778)
							(mid -0.249642 -0.249642)
							(end -0.1778 -0.2794)
						)
						(arc
							(start 0.1778 -0.2794)
							(mid 0.249642 -0.249642)
							(end 0.2794 -0.1778)
						)
						(arc
							(start 0.2794 0.1778)
							(mid 0.249642 0.249642)
							(end 0.1778 0.2794)
						)
					)
					(width 0)
					(fill yes)
				)
			)
		)
		(pad "2" smd custom
			(at 0 0.4445 90)
			(size 0.1397 0.1397)
			(layers "B.Cu" "B.Mask" "B.Paste")
			(net "A_P12V_STBY_FP_TRIGGER")
			(options
				(clearance outline)
				(anchor circle)
			)
			(primitives
				(gr_poly
					(pts
						(arc
							(start -0.1778 0.2794)
							(mid -0.249642 0.249642)
							(end -0.2794 0.1778)
						)
						(arc
							(start -0.2794 -0.1778)
							(mid -0.249642 -0.249642)
							(end -0.1778 -0.2794)
						)
						(arc
							(start 0.1778 -0.2794)
							(mid 0.249642 -0.249642)
							(end 0.2794 -0.1778)
						)
						(arc
							(start 0.2794 0.1778)
							(mid 0.249642 0.249642)
							(end 0.1778 0.2794)
						)
					)
					(width 0)
					(fill yes)
				)
			)
		)
	)
)
